(kicad_pcb
	(version 20260206)
	(generator "pcbnew")
	(generator_version "10.0")
	(general
		(thickness 1.6)
		(legacy_teardrops no)
	)
	(paper "A4")
	(title_block
		(title "timecard-production-celestica-r4006 — R4006-B0001-02_R01.brd")
		(comment 1 "Time Appliance Project (Time Card) / footprints 150-154 of 1113")
	)
	(layers
		(0 "F.Cu" signal "TOP")
		(4 "In1.Cu" signal "L02_GND1")
		(6 "In2.Cu" signal "L03_SIG1")
		(8 "In3.Cu" signal "L04_GND2")
		(10 "In4.Cu" signal "L05_VCC1")
		(12 "In5.Cu" signal "L06_VCC2")
		(14 "In6.Cu" signal "L07_GND3")
		(16 "In7.Cu" signal "L08_SIG2")
		(18 "In8.Cu" signal "L09_GND4")
		(2 "B.Cu" signal "BOTTOM")
		(9 "F.Adhes" user "F.Adhesive")
		(11 "B.Adhes" user "B.Adhesive")
		(13 "F.Paste" user "Package Geometry/Pastemask Top")
		(15 "B.Paste" user "Package Geometry/Pastemask Bottom")
		(5 "F.SilkS" user "Ref Des/Silkscreen Top")
		(7 "B.SilkS" user "Ref Des/Silkscreen Bottom")
		(1 "F.Mask" user "Board Geometry/Soldermask Top")
		(3 "B.Mask" user "Board Geometry/Soldermask Bottom")
		(17 "Dwgs.User" user "User.Drawings")
		(19 "Cmts.User" user "User.Comments")
		(21 "Eco1.User" user "User.Eco1")
		(23 "Eco2.User" user "User.Eco2")
		(25 "Edge.Cuts" user "Board Geometry/Outline")
		(27 "Margin" user)
		(31 "F.CrtYd" user "Package Geometry/Place Bound Top")
		(29 "B.CrtYd" user "Package Geometry/Place Bound Bottom")
		(35 "F.Fab" user "Ref Des/Assembly Top")
		(33 "B.Fab" user "Ref Des/Assembly Bottom")
	)
	(footprint ""
		(layer "F.Cu")
		(at 13.899896 -18.10004 -90)
		(property "Reference" "U14"
			(at 3.91541 0.945896 0)
			(unlocked yes)
			(layer "F.SilkS")
			(effects
				(font
					(size 0.7874 0.5842)
					(thickness 0.1524)
				)
			)
		)
		(property "Value" ""
			(at 0 0 270)
			(layer "F.Fab")
			(effects
				(font
					(size 1.27 1.27)
				)
			)
		)
		(property "Device Type" "74HCT2G125DP_TSSOP8-G220-00055A"
			(at 0 2.413 270)
			(unlocked yes)
			(layer "F.Fab")
			(hide yes)
			(effects
				(font
					(size 0.7874 0.5842)
					(thickness 0.1524)
				)
			)
		)
		(property "User Part Number" "PARTNUM*"
			(at 0 3.6068 270)
			(unlocked yes)
			(layer "Cmts.User")
			(hide yes)
			(effects
				(font
					(size 0.7874 0.5842)
					(thickness 0.1524)
				)
			)
		)
		(duplicate_pad_numbers_are_jumpers no)
		(fp_line
			(start -2.426716 1.304036)
			(end -2.426716 -1.304036)
			(stroke
				(width 0.1)
				(type default)
			)
			(layer "F.SilkS")
		)
		(fp_line
			(start 2.426716 1.304036)
			(end -2.426716 1.304036)
			(stroke
				(width 0.1)
				(type default)
			)
			(layer "F.SilkS")
		)
		(fp_line
			(start -2.426716 -1.304036)
			(end 2.426716 -1.304036)
			(stroke
				(width 0.1)
				(type default)
			)
			(layer "F.SilkS")
		)
		(fp_line
			(start 2.426716 -1.304036)
			(end 2.426716 1.304036)
			(stroke
				(width 0.1)
				(type default)
			)
			(layer "F.SilkS")
		)
		(fp_poly
			(pts
				(arc
					(start -2.98196 -1.594104)
					(mid -2.98196 -0.832104)
					(end -2.98196 -1.594104)
				)
			)
			(stroke
				(width 0)
				(type default)
			)
			(fill yes)
			(layer "F.SilkS")
		)
		(fp_poly
			(pts
				(xy -2.680716 1.558036) (xy 2.680716 1.558036) (xy 2.680716 -1.558036) (xy -2.680716 -1.558036)
			)
			(stroke
				(width 0)
				(type default)
			)
			(fill no)
			(layer "F.CrtYd")
		)
		(fp_line
			(start -1.199896 1.050036)
			(end 1.199896 1.050036)
			(stroke
				(width 0.1)
				(type default)
			)
			(layer "F.Fab")
		)
		(fp_line
			(start 1.199896 1.050036)
			(end 1.199896 -1.050036)
			(stroke
				(width 0.1)
				(type default)
			)
			(layer "F.Fab")
		)
		(fp_line
			(start -1.199896 -1.050036)
			(end -1.199896 1.050036)
			(stroke
				(width 0.1)
				(type default)
			)
			(layer "F.Fab")
		)
		(fp_line
			(start 1.199896 -1.050036)
			(end -1.199896 -1.050036)
			(stroke
				(width 0.1)
				(type default)
			)
			(layer "F.Fab")
		)
		(fp_poly
			(pts
				(arc
					(start -1.94437 -1.338326)
					(mid -1.94437 -0.576326)
					(end -1.94437 -1.338326)
				)
			)
			(stroke
				(width 0)
				(type default)
			)
			(fill yes)
			(layer "F.Fab")
		)
		(fp_text user "4"
			(at -2.208022 1.834896 0)
			(unlocked yes)
			(layer "F.SilkS")
			(effects
				(font
					(size 0.635 0.4064)
					(thickness 0.1524)
				)
			)
		)
		(fp_text user "5"
			(at 2.71399 1.834896 0)
			(unlocked yes)
			(layer "F.SilkS")
			(effects
				(font
					(size 0.635 0.4064)
					(thickness 0.1524)
				)
			)
		)
		(fp_text user "8"
			(at 3.125978 -1.975104 0)
			(unlocked yes)
			(layer "F.SilkS")
			(effects
				(font
					(size 0.635 0.4064)
					(thickness 0.1524)
				)
			)
		)
		(fp_text user "4"
			(at -1.781302 1.199896 0)
			(unlocked yes)
			(layer "F.Fab")
			(effects
				(font
					(size 0.7874 0.5842)
					(thickness 0.1524)
				)
			)
		)
		(fp_text user "5"
			(at 1.947926 0.710184 0)
			(unlocked yes)
			(layer "F.Fab")
			(effects
				(font
					(size 0.7874 0.5842)
					(thickness 0.1524)
				)
			)
		)
		(fp_text user "8"
			(at 1.96088 -0.910844 0)
			(unlocked yes)
			(layer "F.Fab")
			(effects
				(font
					(size 0.7874 0.5842)
					(thickness 0.1524)
				)
			)
		)
		(pad "1" smd rect
			(at -1.690116 -0.749808 270)
			(size 0.9652 0.3048)
			(layers "F.Cu" "F.Mask" "F.Paste")
			(net "SMA4_SIG_OUT_BF_EN_N")
		)
		(pad "2" smd rect
			(at -1.690116 -0.249936 270)
			(size 0.9652 0.3048)
			(layers "F.Cu" "F.Mask" "F.Paste")
			(net "UNNAMED_12_74HCT2G125DPTSSOP8_3")
		)
		(pad "3" smd rect
			(at -1.690116 0.249936 270)
			(size 0.9652 0.3048)
			(layers "F.Cu" "F.Mask" "F.Paste")
			(net "BF_ANT4_IN")
		)
		(pad "4" smd rect
			(at -1.690116 0.749808 270)
			(size 0.9652 0.3048)
			(layers "F.Cu" "F.Mask" "F.Paste")
			(net "SG")
		)
		(pad "5" smd rect
			(at 1.690116 0.749808 270)
			(size 0.9652 0.3048)
			(layers "F.Cu" "F.Mask" "F.Paste")
			(net "BF_SMA4_SIG_IO_CONN")
		)
		(pad "6" smd rect
			(at 1.690116 0.249936 270)
			(size 0.9652 0.3048)
			(layers "F.Cu" "F.Mask" "F.Paste")
			(net "BF_SMA4_SIG_IO_CONN")
		)
		(pad "7" smd rect
			(at 1.690116 -0.249936 270)
			(size 0.9652 0.3048)
			(layers "F.Cu" "F.Mask" "F.Paste")
			(net "SMA4_SIG_IN_BF_EN_N")
		)
		(pad "8" smd rect
			(at 1.690116 -0.749808 270)
			(size 0.9652 0.3048)
			(layers "F.Cu" "F.Mask" "F.Paste")
			(net "XP3R3V_FPGA")
		)
	)
	(footprint ""
		(layer "F.Cu")
		(at 49.7586 -83.0072 -90)
		(property "Reference" "R422"
			(at -3.3528 -0.19177 90)
			(unlocked yes)
			(layer "F.SilkS")
			(effects
				(font
					(size 0.7874 0.5842)
					(thickness 0.1524)
				)
			)
		)
		(property "Value" "VAL*"
			(at 0.02032 2.13233 270)
			(unlocked yes)
			(layer "F.Fab")
			(hide yes)
			(effects
				(font
					(size 0.7874 0.5842)
					(thickness 0.1524)
				)
			)
		)
		(property "Tolerance" "TOL*"
			(at 0.044704 3.05435 270)
			(unlocked yes)
			(layer "Cmts.User")
			(hide yes)
			(effects
				(font
					(size 0.7874 0.5842)
					(thickness 0.1524)
				)
			)
		)
		(property "User Part Number" "PARTNUM*"
			(at 0.02032 4.024884 270)
			(unlocked yes)
			(layer "Cmts.User")
			(hide yes)
			(effects
				(font
					(size 0.7874 0.5842)
					(thickness 0.1524)
				)
			)
		)
		(property "Device Type" "RESISTOR-G155-14701-01,4.7KOHMA"
			(at 0.008382 1.210564 270)
			(unlocked yes)
			(layer "F.Fab")
			(hide yes)
			(effects
				(font
					(size 0.7874 0.5842)
					(thickness 0.1524)
				)
			)
		)
		(duplicate_pad_numbers_are_jumpers no)
		(fp_line
			(start -1.143 0.5588)
			(end 1.143 0.5588)
			(stroke
				(width 0.1)
				(type default)
			)
			(layer "F.SilkS")
		)
		(fp_line
			(start 1.143 0.5588)
			(end 1.143 -0.5588)
			(stroke
				(width 0.1)
				(type default)
			)
			(layer "F.SilkS")
		)
		(fp_line
			(start -1.143 -0.5588)
			(end -1.143 0.5588)
			(stroke
				(width 0.1)
				(type default)
			)
			(layer "F.SilkS")
		)
		(fp_line
			(start 1.143 -0.5588)
			(end -1.143 -0.5588)
			(stroke
				(width 0.1)
				(type default)
			)
			(layer "F.SilkS")
		)
		(fp_rect
			(start -1.143 0.5588)
			(end 1.143 -0.5588)
			(stroke
				(width 0)
				(type default)
			)
			(fill no)
			(layer "F.CrtYd")
		)
		(fp_line
			(start -0.508 0.3048)
			(end 0.508 0.3048)
			(stroke
				(width 0.1)
				(type default)
			)
			(layer "F.Fab")
		)
		(fp_line
			(start 0.508 0.3048)
			(end 0.508 -0.3048)
			(stroke
				(width 0.1)
				(type default)
			)
			(layer "F.Fab")
		)
		(fp_line
			(start -0.508 -0.3048)
			(end -0.508 0.3048)
			(stroke
				(width 0.1)
				(type default)
			)
			(layer "F.Fab")
		)
		(fp_line
			(start 0.508 -0.3048)
			(end -0.508 -0.3048)
			(stroke
				(width 0.1)
				(type default)
			)
			(layer "F.Fab")
		)
		(pad "1" smd rect
			(at -0.5334 0 270)
			(size 0.7112 0.6096)
			(layers "F.Cu" "F.Mask" "F.Paste")
			(net "XP3R3V_FPGA")
		)
		(pad "2" smd rect
			(at 0.5334 0 270)
			(size 0.7112 0.6096)
			(layers "F.Cu" "F.Mask" "F.Paste")
			(net "FPGA_IN_LM75B_INT2_N")
		)
		(zone
			(layer "F.Cu")
			(hatch none 0.5)
			(connect_pads
				(clearance 0)
			)
			(min_thickness 0.25)
			(keepout
				(tracks not_allowed)
				(vias allowed)
				(pads allowed)
				(copperpour not_allowed)
				(footprints allowed)
			)
			(placement
				(enabled no)
				(sheetname "")
			)
			(fill
				(thermal_gap 0.5)
				(thermal_bridge_width 0.5)
				(island_removal_mode 0)
			)
			(polygon
				(pts
					(xy 49.4538 -83.0834) (xy 49.4538 -82.931) (xy 50.0634 -82.931) (xy 50.0634 -83.0834)
				)
			)
		)
		(zone
			(layer "F.Cu")
			(hatch none 0.5)
			(connect_pads
				(clearance 0)
			)
			(min_thickness 0.25)
			(keepout
				(tracks allowed)
				(vias not_allowed)
				(pads allowed)
				(copperpour not_allowed)
				(footprints allowed)
			)
			(placement
				(enabled no)
				(sheetname "")
			)
			(fill
				(thermal_gap 0.5)
				(thermal_bridge_width 0.5)
				(island_removal_mode 0)
			)
			(polygon
				(pts
					(xy 49.4538 -83.0834) (xy 49.4538 -82.931) (xy 50.0634 -82.931) (xy 50.0634 -83.0834)
				)
			)
		)
	)
	(footprint ""
		(layer "F.Cu")
		(at 68.216018 -65.009522)
		(property "Reference" "ME6"
			(at -4.444238 2.072132 0)
			(unlocked yes)
			(layer "F.SilkS")
			(effects
				(font
					(size 0.7874 0.5842)
					(thickness 0.1524)
				)
			)
		)
		(property "Value" ""
			(at 0 0 0)
			(layer "F.Fab")
			(effects
				(font
					(size 1.27 1.27)
				)
			)
		)
		(duplicate_pad_numbers_are_jumpers no)
		(fp_poly
			(pts
				(arc
					(start 3.556 0)
					(mid -3.556 0)
					(end 3.556 0)
				)
			)
			(stroke
				(width 0)
				(type default)
			)
			(fill no)
			(layer "B.CrtYd")
		)
		(fp_poly
			(pts
				(arc
					(start 3.556 0)
					(mid -3.556 0)
					(end 3.556 0)
				)
			)
			(stroke
				(width 0)
				(type default)
			)
			(fill no)
			(layer "F.CrtYd")
		)
		(fp_circle
			(center 0 0)
			(end 3.048 0)
			(stroke
				(width 0.1)
				(type default)
			)
			(fill no)
			(layer "B.Fab")
		)
		(fp_circle
			(center 0 0)
			(end 3.048 0)
			(stroke
				(width 0.1)
				(type default)
			)
			(fill no)
			(layer "F.Fab")
		)
		(pad "" np_thru_hole circle
			(at 0 0)
			(size 2.286 2.286)
			(drill 2.54)
			(layers "*.Cu" "*.Mask")
			(padstack
				(mode front_inner_back)
				(layer "Inner"
					(shape circle)
					(size 2.286 2.286)
					(clearance 0.4445)
				)
				(layer "B.Cu"
					(shape circle)
					(size 2.286 2.286)
				)
			)
		)
		(zone
			(layers "F.Cu" "B.Cu" "In1.Cu" "In2.Cu" "In3.Cu" "In4.Cu" "In5.Cu" "In6.Cu"
				"In7.Cu" "In8.Cu"
			)
			(hatch none 0.5)
			(connect_pads
				(clearance 0)
			)
			(min_thickness 0.25)
			(keepout
				(tracks not_allowed)
				(vias allowed)
				(pads allowed)
				(copperpour not_allowed)
				(footprints allowed)
			)
			(placement
				(enabled no)
				(sheetname "")
			)
			(fill
				(thermal_gap 0.5)
				(thermal_bridge_width 0.5)
				(island_removal_mode 0)
			)
			(polygon
				(pts
					(arc
						(start 69.790818 -65.009522)
						(mid 66.641218 -65.009522)
						(end 69.790818 -65.009522)
					)
				)
			)
		)
	)
	(footprint ""
		(layer "F.Cu")
		(at 19.468338 -44.45 180)
		(property "Reference" "R394"
			(at -3.518662 -0.16637 0)
			(unlocked yes)
			(layer "F.SilkS")
			(effects
				(font
					(size 0.7874 0.5842)
					(thickness 0.1524)
				)
			)
		)
		(property "Value" "VAL*"
			(at 0.02032 2.13233 180)
			(unlocked yes)
			(layer "F.Fab")
			(hide yes)
			(effects
				(font
					(size 0.7874 0.5842)
					(thickness 0.1524)
				)
			)
		)
		(property "Tolerance" "TOL*"
			(at 0.044704 3.05435 180)
			(unlocked yes)
			(layer "Cmts.User")
			(hide yes)
			(effects
				(font
					(size 0.7874 0.5842)
					(thickness 0.1524)
				)
			)
		)
		(property "User Part Number" "PARTNUM*"
			(at 0.02032 4.024884 180)
			(unlocked yes)
			(layer "Cmts.User")
			(hide yes)
			(effects
				(font
					(size 0.7874 0.5842)
					(thickness 0.1524)
				)
			)
		)
		(property "Device Type" "RESISTOR-G155-133R0-01,33OHM,1%"
			(at 0.008382 1.210564 180)
			(unlocked yes)
			(layer "F.Fab")
			(hide yes)
			(effects
				(font
					(size 0.7874 0.5842)
					(thickness 0.1524)
				)
			)
		)
		(duplicate_pad_numbers_are_jumpers no)
		(fp_line
			(start 1.143 0.5588)
			(end 1.143 -0.5588)
			(stroke
				(width 0.1)
				(type default)
			)
			(layer "F.SilkS")
		)
		(fp_line
			(start 1.143 -0.5588)
			(end -1.143 -0.5588)
			(stroke
				(width 0.1)
				(type default)
			)
			(layer "F.SilkS")
		)
		(fp_line
			(start -1.143 0.5588)
			(end 1.143 0.5588)
			(stroke
				(width 0.1)
				(type default)
			)
			(layer "F.SilkS")
		)
		(fp_line
			(start -1.143 -0.5588)
			(end -1.143 0.5588)
			(stroke
				(width 0.1)
				(type default)
			)
			(layer "F.SilkS")
		)
		(fp_rect
			(start -1.143 -0.5588)
			(end 1.143 0.5588)
			(stroke
				(width 0)
				(type default)
			)
			(fill no)
			(layer "F.CrtYd")
		)
		(fp_line
			(start 0.508 0.3048)
			(end 0.508 -0.3048)
			(stroke
				(width 0.1)
				(type default)
			)
			(layer "F.Fab")
		)
		(fp_line
			(start 0.508 -0.3048)
			(end -0.508 -0.3048)
			(stroke
				(width 0.1)
				(type default)
			)
			(layer "F.Fab")
		)
		(fp_line
			(start -0.508 0.3048)
			(end 0.508 0.3048)
			(stroke
				(width 0.1)
				(type default)
			)
			(layer "F.Fab")
		)
		(fp_line
			(start -0.508 -0.3048)
			(end -0.508 0.3048)
			(stroke
				(width 0.1)
				(type default)
			)
			(layer "F.Fab")
		)
		(pad "1" smd rect
			(at -0.5334 0 180)
			(size 0.7112 0.6096)
			(layers "F.Cu" "F.Mask" "F.Paste")
			(net "SMA4_LED_BLUE_N")
		)
		(pad "2" smd rect
			(at 0.5334 0 180)
			(size 0.7112 0.6096)
			(layers "F.Cu" "F.Mask" "F.Paste")
			(net "UNNAMED_14_LED4PV14_I268_1")
		)
		(zone
			(layer "F.Cu")
			(hatch none 0.5)
			(connect_pads
				(clearance 0)
			)
			(min_thickness 0.25)
			(keepout
				(tracks allowed)
				(vias not_allowed)
				(pads allowed)
				(copperpour not_allowed)
				(footprints allowed)
			)
			(placement
				(enabled no)
				(sheetname "")
			)
			(fill
				(thermal_gap 0.5)
				(thermal_bridge_width 0.5)
				(island_removal_mode 0)
			)
			(polygon
				(pts
					(xy 19.544538 -44.1452) (xy 19.544538 -44.7548) (xy 19.392138 -44.7548) (xy 19.392138 -44.1452)
				)
			)
		)
		(zone
			(layer "F.Cu")
			(hatch none 0.5)
			(connect_pads
				(clearance 0)
			)
			(min_thickness 0.25)
			(keepout
				(tracks not_allowed)
				(vias allowed)
				(pads allowed)
				(copperpour not_allowed)
				(footprints allowed)
			)
			(placement
				(enabled no)
				(sheetname "")
			)
			(fill
				(thermal_gap 0.5)
				(thermal_bridge_width 0.5)
				(island_removal_mode 0)
			)
			(polygon
				(pts
					(xy 19.544538 -44.1452) (xy 19.544538 -44.7548) (xy 19.392138 -44.7548) (xy 19.392138 -44.1452)
				)
			)
		)
	)
	(footprint ""
		(layer "F.Cu")
		(at 117.348 -61.976 90)
		(property "Reference" "R348"
			(at 3.302 0.80137 90)
			(unlocked yes)
			(layer "F.SilkS")
			(effects
				(font
					(size 0.7874 0.5842)
					(thickness 0.1524)
				)
			)
		)
		(property "Value" "VAL*"
			(at 0.02032 2.13233 90)
			(unlocked yes)
			(layer "F.Fab")
			(hide yes)
			(effects
				(font
					(size 0.7874 0.5842)
					(thickness 0.1524)
				)
			)
		)
		(property "Tolerance" "TOL*"
			(at 0.044704 3.05435 90)
			(unlocked yes)
			(layer "Cmts.User")
			(hide yes)
			(effects
				(font
					(size 0.7874 0.5842)
					(thickness 0.1524)
				)
			)
		)
		(property "User Part Number" "PARTNUM*"
			(at 0.02032 4.024884 90)
			(unlocked yes)
			(layer "Cmts.User")
			(hide yes)
			(effects
				(font
					(size 0.7874 0.5842)
					(thickness 0.1524)
				)
			)
		)
		(property "Device Type" "RESISTOR-G155-133R0-01,33OHM,1%"
			(at 0.008382 1.210564 90)
			(unlocked yes)
			(layer "F.Fab")
			(hide yes)
			(effects
				(font
					(size 0.7874 0.5842)
					(thickness 0.1524)
				)
			)
		)
		(duplicate_pad_numbers_are_jumpers no)
		(fp_line
			(start 1.143 -0.5588)
			(end -1.143 -0.5588)
			(stroke
				(width 0.1)
				(type default)
			)
			(layer "F.SilkS")
		)
		(fp_line
			(start -1.143 -0.5588)
			(end -1.143 0.5588)
			(stroke
				(width 0.1)
				(type default)
			)
			(layer "F.SilkS")
		)
		(fp_line
			(start 1.143 0.5588)
			(end 1.143 -0.5588)
			(stroke
				(width 0.1)
				(type default)
			)
			(layer "F.SilkS")
		)
		(fp_line
			(start -1.143 0.5588)
			(end 1.143 0.5588)
			(stroke
				(width 0.1)
				(type default)
			)
			(layer "F.SilkS")
		)
		(fp_poly
			(pts
				(xy -1.143 0.5588) (xy 1.143 0.5588) (xy 1.143 -0.5588) (xy -1.143 -0.5588)
			)
			(stroke
				(width 0)
				(type default)
			)
			(fill no)
			(layer "F.CrtYd")
		)
		(fp_line
			(start 0.508 -0.3048)
			(end -0.508 -0.3048)
			(stroke
				(width 0.1)
				(type default)
			)
			(layer "F.Fab")
		)
		(fp_line
			(start -0.508 -0.3048)
			(end -0.508 0.3048)
			(stroke
				(width 0.1)
				(type default)
			)
			(layer "F.Fab")
		)
		(fp_line
			(start 0.508 0.3048)
			(end 0.508 -0.3048)
			(stroke
				(width 0.1)
				(type default)
			)
			(layer "F.Fab")
		)
		(fp_line
			(start -0.508 0.3048)
			(end 0.508 0.3048)
			(stroke
				(width 0.1)
				(type default)
			)
			(layer "F.Fab")
		)
		(pad "1" smd rect
			(at -0.5334 0 90)
			(size 0.7112 0.6096)
			(layers "F.Cu" "F.Mask" "F.Paste")
			(net "FPGA_D03")
		)
		(pad "2" smd rect
			(at 0.5334 0 90)
			(size 0.7112 0.6096)
			(layers "F.Cu" "F.Mask" "F.Paste")
			(net "FPGA_FLASH_DQ3")
		)
		(zone
			(layer "F.Cu")
			(hatch none 0.5)
			(connect_pads
				(clearance 0)
			)
			(min_thickness 0.25)
			(keepout
				(tracks not_allowed)
				(vias allowed)
				(pads allowed)
				(copperpour not_allowed)
				(footprints allowed)
			)
			(placement
				(enabled no)
				(sheetname "")
			)
			(fill
				(thermal_gap 0.5)
				(thermal_bridge_width 0.5)
				(island_removal_mode 0)
			)
			(polygon
				(pts
					(xy 117.6528 -61.8998) (xy 117.6528 -62.0522) (xy 117.0432 -62.0522) (xy 117.0432 -61.8998)
				)
			)
		)
		(zone
			(layer "F.Cu")
			(hatch none 0.5)
			(connect_pads
				(clearance 0)
			)
			(min_thickness 0.25)
			(keepout
				(tracks allowed)
				(vias not_allowed)
				(pads allowed)
				(copperpour not_allowed)
				(footprints allowed)
			)
			(placement
				(enabled no)
				(sheetname "")
			)
			(fill
				(thermal_gap 0.5)
				(thermal_bridge_width 0.5)
				(island_removal_mode 0)
			)
			(polygon
				(pts
					(xy 117.6528 -61.8998) (xy 117.6528 -62.0522) (xy 117.0432 -62.0522) (xy 117.0432 -61.8998)
				)
			)
		)
	)
)
